(kicad_pcb
	(version 20241229)
	(generator "pcbnew")
	(generator_version "9.0")
	(general
		(thickness 1.599998)
		(legacy_teardrops no)
	)
	(paper "A4")
	(title_block
		(title "Artix - Datacenter Secure Control Module (DC-SCM)")
		(date "2024-11-06")
		(rev "1.1.3")
		(comment 9 "footprints 208-212 of 544")
	)
	(layers
		(0 "F.Cu" signal)
		(4 "In1.Cu" signal)
		(6 "In2.Cu" signal)
		(8 "In3.Cu" signal)
		(10 "In4.Cu" signal)
		(12 "In5.Cu" signal)
		(14 "In6.Cu" signal)
		(2 "B.Cu" signal)
		(9 "F.Adhes" user "F.Adhesive")
		(11 "B.Adhes" user "B.Adhesive")
		(13 "F.Paste" user)
		(15 "B.Paste" user)
		(5 "F.SilkS" user "F.Silkscreen")
		(7 "B.SilkS" user "B.Silkscreen")
		(1 "F.Mask" user)
		(3 "B.Mask" user)
		(17 "Dwgs.User" user "User.Drawings")
		(19 "Cmts.User" user "User.Comments")
		(21 "Eco1.User" user "User.Eco1")
		(23 "Eco2.User" user "User.Eco2")
		(25 "Edge.Cuts" user)
		(27 "Margin" user)
		(31 "F.CrtYd" user "F.Courtyard")
		(29 "B.CrtYd" user "B.Courtyard")
		(35 "F.Fab" user)
		(33 "B.Fab" user)
	)
	(footprint "antmicro-footprints:Conn_Molex_Pico-Lock_1x2_504050-0291"
		(layer "F.Cu")
		(at 143.2 141.7 90)
		(property "Reference" "J10"
			(at 3.75 -2.95 180)
			(layer "F.SilkS")
			(effects
				(font
					(size 0.7 0.7)
					(thickness 0.15)
				)
				(justify left bottom)
			)
		)
		(property "Value" "Molex_Pico-Lock_1x2_504050-0291"
			(at -0.749 4.35 90)
			(layer "F.Fab")
			(effects
				(font
					(size 0.7 0.7)
					(thickness 0.15)
				)
				(justify left bottom)
			)
		)
		(property "Datasheet" "https://www.molex.com/en-us/products/part-detail-pdf/5040500291?display=pdf"
			(at 0 0 90)
			(layer "F.Fab")
			(hide yes)
			(effects
				(font
					(size 1.27 1.27)
					(thickness 0.15)
				)
			)
		)
		(property "Description" "Connector Header Surface Mount, Right Angle 2 position 0.059\" (1.50mm)"
			(at 0 0 90)
			(layer "F.Fab")
			(hide yes)
			(effects
				(font
					(size 1.27 1.27)
					(thickness 0.15)
				)
			)
		)
		(property "Author" "Antmicro"
			(at 284.9 -1.5 0)
			(layer "F.Fab")
			(hide yes)
			(effects
				(font
					(size 1 1)
					(thickness 0.15)
				)
			)
		)
		(property "License" "Apache-2.0"
			(at 284.9 -1.5 0)
			(layer "F.Fab")
			(hide yes)
			(effects
				(font
					(size 1 1)
					(thickness 0.15)
				)
			)
		)
		(property "MPN" "504050-0291"
			(at 284.9 -1.5 0)
			(layer "F.Fab")
			(hide yes)
			(effects
				(font
					(size 1 1)
					(thickness 0.15)
				)
			)
		)
		(property "Manufacturer" "Molex"
			(at 284.9 -1.5 0)
			(layer "F.Fab")
			(hide yes)
			(effects
				(font
					(size 1 1)
					(thickness 0.15)
				)
			)
		)
		(sheetname "/Power supply/")
		(sheetfile "power-supply.kicad_sch")
		(attr smd)
		(fp_line
			(start 3.374 -2.86)
			(end 3.374 1.088)
			(stroke
				(width 0.15)
				(type solid)
			)
			(layer "F.SilkS")
		)
		(fp_line
			(start 1.399 -2.86)
			(end 3.374 -2.86)
			(stroke
				(width 0.15)
				(type solid)
			)
			(layer "F.SilkS")
		)
		(fp_line
			(start -3.374 -2.86)
			(end -1.4 -2.86)
			(stroke
				(width 0.15)
				(type solid)
			)
			(layer "F.SilkS")
		)
		(fp_line
			(start -3.374 1.088)
			(end -3.374 -2.86)
			(stroke
				(width 0.15)
				(type solid)
			)
			(layer "F.SilkS")
		)
		(fp_line
			(start 1.649 1.289)
			(end -1.639 1.289)
			(stroke
				(width 0.15)
				(type solid)
			)
			(layer "F.SilkS")
		)
		(fp_line
			(start 1.649 1.289)
			(end 1.649 3.228)
			(stroke
				(width 0.15)
				(type solid)
			)
			(layer "F.SilkS")
		)
		(fp_line
			(start -1.639 3.239)
			(end -1.639 1.289)
			(stroke
				(width 0.15)
				(type solid)
			)
			(layer "F.SilkS")
		)
		(fp_circle
			(center -1.249 -3.15)
			(end -1.199 -3.15)
			(stroke
				(width 0.15)
				(type solid)
			)
			(fill yes)
			(layer "F.SilkS")
		)
		(fp_line
			(start 3.621 -3.61)
			(end 3.621 1.18)
			(stroke
				(width 0.05)
				(type solid)
			)
			(layer "F.CrtYd")
		)
		(fp_line
			(start -3.629 -3.61)
			(end 3.621 -3.61)
			(stroke
				(width 0.05)
				(type solid)
			)
			(layer "F.CrtYd")
		)
		(fp_line
			(start 4.231 1.18)
			(end 4.231 3.47)
			(stroke
				(width 0.05)
				(type solid)
			)
			(layer "F.CrtYd")
		)
		(fp_line
			(start 3.621 1.18)
			(end 4.231 1.18)
			(stroke
				(width 0.05)
				(type solid)
			)
			(layer "F.CrtYd")
		)
		(fp_line
			(start -3.629 1.18)
			(end -3.629 -3.61)
			(stroke
				(width 0.05)
				(type solid)
			)
			(layer "F.CrtYd")
		)
		(fp_line
			(start -4.249 1.18)
			(end -3.629 1.18)
			(stroke
				(width 0.05)
				(type solid)
			)
			(layer "F.CrtYd")
		)
		(fp_line
			(start 4.231 3.47)
			(end -4.249 3.47)
			(stroke
				(width 0.05)
				(type solid)
			)
			(layer "F.CrtYd")
		)
		(fp_line
			(start -4.249 3.47)
			(end -4.249 1.18)
			(stroke
				(width 0.05)
				(type solid)
			)
			(layer "F.CrtYd")
		)
		(fp_line
			(start 3.374 -2.86)
			(end 3.374 3.239)
			(stroke
				(width 0.15)
				(type solid)
			)
			(layer "F.Fab")
		)
		(fp_line
			(start -3.374 -2.86)
			(end 3.374 -2.86)
			(stroke
				(width 0.15)
				(type solid)
			)
			(layer "F.Fab")
		)
		(fp_line
			(start 1.75 1.188)
			(end -1.749 1.188)
			(stroke
				(width 0.15)
				(type solid)
			)
			(layer "F.Fab")
		)
		(fp_line
			(start 1.75 1.188)
			(end 1.75 3.239)
			(stroke
				(width 0.15)
				(type solid)
			)
			(layer "F.Fab")
		)
		(fp_line
			(start 1.75 3.239)
			(end 3.374 3.239)
			(stroke
				(width 0.15)
				(type solid)
			)
			(layer "F.Fab")
		)
		(fp_line
			(start -3.374 3.239)
			(end -3.374 -2.86)
			(stroke
				(width 0.15)
				(type solid)
			)
			(layer "F.Fab")
		)
		(fp_line
			(start -3.374 3.239)
			(end -1.749 3.239)
			(stroke
				(width 0.15)
				(type solid)
			)
			(layer "F.Fab")
		)
		(fp_line
			(start -1.749 3.249)
			(end -1.749 1.188)
			(stroke
				(width 0.15)
				(type solid)
			)
			(layer "F.Fab")
		)
		(fp_text user "${REFERENCE}"
			(at -3.481 10.175 90)
			(layer "F.Fab")
			(effects
				(font
					(size 0.7 0.7)
					(thickness 0.15)
				)
				(justify left bottom)
			)
		)
		(fp_text user "License: Apache-2.0"
			(at -3.481 12.573 90)
			(layer "F.Fab")
			(effects
				(font
					(size 0.7 0.7)
					(thickness 0.15)
				)
				(justify left bottom)
			)
		)
		(fp_text user "Author: Antmicro"
			(at -3.481 11.374 90)
			(layer "F.Fab")
			(effects
				(font
					(size 0.7 0.7)
					(thickness 0.15)
				)
				(justify left bottom)
			)
		)
		(pad "1" smd roundrect
			(at -0.749 -2.85 90)
			(size 0.6 1)
			(layers "F.Cu" "F.Mask" "F.Paste")
			(roundrect_rratio 0.25)
			(net 287 "3V0_BAT")
			(pinfunction "1")
			(pintype "passive")
		)
		(pad "2" smd roundrect
			(at 0.75 -2.85 90)
			(size 0.6 1)
			(layers "F.Cu" "F.Mask" "F.Paste")
			(roundrect_rratio 0.25)
			(net 1 "GND")
			(pinfunction "2")
			(pintype "passive")
		)
		(pad "MP1" smd roundrect
			(at -3.354 2.338 90)
			(size 1.25 1.8)
			(layers "F.Cu" "F.Mask" "F.Paste")
			(roundrect_rratio 0.25)
			(net 1 "GND")
			(pinfunction "MP")
			(pintype "passive")
		)
		(pad "MP2" smd roundrect
			(at 3.356 2.338 90)
			(size 1.25 1.8)
			(layers "F.Cu" "F.Mask" "F.Paste")
			(roundrect_rratio 0.25)
			(net 1 "GND")
			(pinfunction "MP2")
			(pintype "passive")
		)
	)
	(footprint "antmicro-footprints:TP_SMD_1mm"
		(layer "F.Cu")
		(at 144.54 114.4658)
		(property "Reference" "TP3"
			(at 0.56 0.4342 0)
			(layer "F.SilkS")
			(effects
				(font
					(size 0.7 0.7)
					(thickness 0.15)
				)
				(justify left bottom)
			)
		)
		(property "Value" "TP_1mm_SMD"
			(at 0 1.4 0)
			(layer "F.Fab")
			(effects
				(font
					(size 0.7 0.7)
					(thickness 0.15)
				)
				(justify left bottom)
			)
		)
		(property "Description" "Test point 1mm SMD"
			(at 0 0 0)
			(layer "F.Fab")
			(hide yes)
			(effects
				(font
					(size 1.27 1.27)
					(thickness 0.15)
				)
			)
		)
		(property "Author" "Antmicro"
			(at 0 0 0)
			(layer "F.Fab")
			(hide yes)
			(effects
				(font
					(size 1 1)
					(thickness 0.15)
				)
			)
		)
		(property "License" "Apache-2.0"
			(at 0 0 0)
			(layer "F.Fab")
			(hide yes)
			(effects
				(font
					(size 1 1)
					(thickness 0.15)
				)
			)
		)
		(property "MPN" ""
			(at 0 0 0)
			(layer "F.Fab")
			(hide yes)
			(effects
				(font
					(size 1 1)
					(thickness 0.15)
				)
			)
		)
		(property "Manufacturer" ""
			(at 0 0 0)
			(layer "F.Fab")
			(hide yes)
			(effects
				(font
					(size 1 1)
					(thickness 0.15)
				)
			)
		)
		(sheetname "/Interfaces/")
		(sheetfile "interfaces.kicad_sch")
		(attr exclude_from_pos_files exclude_from_bom)
		(fp_circle
			(center 0 0)
			(end 0.6 0)
			(stroke
				(width 0.05)
				(type default)
			)
			(fill no)
			(layer "F.CrtYd")
		)
		(pad "1" smd circle
			(at 0 0)
			(size 1 1)
			(layers "F.Cu" "F.Mask")
			(net 402 "Net-(U1-DS)")
			(pinfunction "1")
			(pintype "passive")
		)
	)
	(footprint "antmicro-footprints:C_0402_1005Metric"
		(layer "F.Cu")
		(at 82.665 163.565)
		(descr "Capacitor SMD 0402")
		(tags "capacitor SMD 0402")
		(property "Reference" "C251"
			(at 0.835 -0.065 0)
			(layer "F.SilkS")
			(effects
				(font
					(size 0.7 0.7)
					(thickness 0.15)
				)
				(justify left bottom)
			)
		)
		(property "Value" "C_100n_0402"
			(at 0 1.4 0)
			(layer "F.Fab")
			(effects
				(font
					(size 0.7 0.7)
					(thickness 0.15)
				)
				(justify left bottom)
			)
		)
		(property "Datasheet" "https://www.murata.com/products/productdetail?partno=GRM155R61H104KE14%23"
			(at 0 0 0)
			(layer "F.Fab")
			(hide yes)
			(effects
				(font
					(size 1.27 1.27)
					(thickness 0.15)
				)
			)
		)
		(property "Description" "SMD Multilayer Ceramic Capacitor, 0.1 µF, 50 V, 0402 [1005 Metric], ± 10%, X5R, GRM Series"
			(at 0 0 0)
			(layer "F.Fab")
			(hide yes)
			(effects
				(font
					(size 1.27 1.27)
					(thickness 0.15)
				)
			)
		)
		(property "Author" "Antmicro"
			(at 0 0 0)
			(layer "F.Fab")
			(hide yes)
			(effects
				(font
					(size 1 1)
					(thickness 0.15)
				)
			)
		)
		(property "Dielectric" "X5R"
			(at 0 0 0)
			(layer "F.Fab")
			(hide yes)
			(effects
				(font
					(size 1 1)
					(thickness 0.15)
				)
			)
		)
		(property "License" "Apache-2.0"
			(at 0 0 0)
			(layer "F.Fab")
			(hide yes)
			(effects
				(font
					(size 1 1)
					(thickness 0.15)
				)
			)
		)
		(property "MPN" "GRM155R61H104KE14D"
			(at 0 0 0)
			(layer "F.Fab")
			(hide yes)
			(effects
				(font
					(size 1 1)
					(thickness 0.15)
				)
			)
		)
		(property "Manufacturer" "Murata"
			(at 0 0 0)
			(layer "F.Fab")
			(hide yes)
			(effects
				(font
					(size 1 1)
					(thickness 0.15)
				)
			)
		)
		(property "Val" "100n"
			(at 0 0 0)
			(layer "F.Fab")
			(hide yes)
			(effects
				(font
					(size 1 1)
					(thickness 0.15)
				)
			)
		)
		(property "Voltage" "50V"
			(at 0 0 0)
			(layer "F.Fab")
			(hide yes)
			(effects
				(font
					(size 1 1)
					(thickness 0.15)
				)
			)
		)
		(sheetname "/Interfaces/")
		(sheetfile "interfaces.kicad_sch")
		(attr smd)
		(fp_rect
			(start -0.925 -0.47)
			(end 0.925 0.47)
			(stroke
				(width 0.05)
				(type default)
			)
			(fill no)
			(layer "F.CrtYd")
		)
		(fp_line
			(start -0.494 -0.25)
			(end 0.504 -0.25)
			(stroke
				(width 0.15)
				(type solid)
			)
			(layer "F.Fab")
		)
		(fp_line
			(start -0.494 0.248)
			(end -0.494 -0.25)
			(stroke
				(width 0.15)
				(type solid)
			)
			(layer "F.Fab")
		)
		(fp_line
			(start 0.504 -0.25)
			(end 0.504 0.248)
			(stroke
				(width 0.15)
				(type solid)
			)
			(layer "F.Fab")
		)
		(fp_line
			(start 0.504 0.248)
			(end -0.494 0.248)
			(stroke
				(width 0.15)
				(type solid)
			)
			(layer "F.Fab")
		)
		(pad "1" smd roundrect
			(at -0.48 0)
			(size 0.59 0.64)
			(layers "F.Cu" "F.Mask" "F.Paste")
			(roundrect_rratio 0.25)
			(net 1 "GND")
			(pintype "passive")
		)
		(pad "2" smd roundrect
			(at 0.48 0)
			(size 0.59 0.64)
			(layers "F.Cu" "F.Mask" "F.Paste")
			(roundrect_rratio 0.25)
			(net 2 "VCC3V3")
			(pintype "passive")
		)
	)
	(footprint "antmicro-footprints:C_0402_1005Metric"
		(layer "F.Cu")
		(at 90.59 165.415 180)
		(descr "Capacitor SMD 0402")
		(tags "capacitor SMD 0402")
		(property "Reference" "C252"
			(at -3.71 -0.91 0)
			(layer "F.SilkS")
			(effects
				(font
					(size 0.7 0.7)
					(thickness 0.15)
				)
				(justify right bottom)
			)
		)
		(property "Value" "C_100n_0402"
			(at 0 1.4 0)
			(layer "F.Fab")
			(effects
				(font
					(size 0.7 0.7)
					(thickness 0.15)
				)
				(justify right bottom)
			)
		)
		(property "Datasheet" "https://www.murata.com/products/productdetail?partno=GRM155R61H104KE14%23"
			(at 0 0 180)
			(layer "F.Fab")
			(hide yes)
			(effects
				(font
					(size 1.27 1.27)
					(thickness 0.15)
				)
			)
		)
		(property "Description" "SMD Multilayer Ceramic Capacitor, 0.1 µF, 50 V, 0402 [1005 Metric], ± 10%, X5R, GRM Series"
			(at 0 0 180)
			(layer "F.Fab")
			(hide yes)
			(effects
				(font
					(size 1.27 1.27)
					(thickness 0.15)
				)
			)
		)
		(property "Author" "Antmicro"
			(at 181.18 330.83 0)
			(layer "F.Fab")
			(hide yes)
			(effects
				(font
					(size 1 1)
					(thickness 0.15)
				)
			)
		)
		(property "Dielectric" "X5R"
			(at 181.18 330.83 0)
			(layer "F.Fab")
			(hide yes)
			(effects
				(font
					(size 1 1)
					(thickness 0.15)
				)
			)
		)
		(property "License" "Apache-2.0"
			(at 181.18 330.83 0)
			(layer "F.Fab")
			(hide yes)
			(effects
				(font
					(size 1 1)
					(thickness 0.15)
				)
			)
		)
		(property "MPN" "GRM155R61H104KE14D"
			(at 181.18 330.83 0)
			(layer "F.Fab")
			(hide yes)
			(effects
				(font
					(size 1 1)
					(thickness 0.15)
				)
			)
		)
		(property "Manufacturer" "Murata"
			(at 181.18 330.83 0)
			(layer "F.Fab")
			(hide yes)
			(effects
				(font
					(size 1 1)
					(thickness 0.15)
				)
			)
		)
		(property "Val" "100n"
			(at 181.18 330.83 0)
			(layer "F.Fab")
			(hide yes)
			(effects
				(font
					(size 1 1)
					(thickness 0.15)
				)
			)
		)
		(property "Voltage" "50V"
			(at 181.18 330.83 0)
			(layer "F.Fab")
			(hide yes)
			(effects
				(font
					(size 1 1)
					(thickness 0.15)
				)
			)
		)
		(sheetname "/Interfaces/")
		(sheetfile "interfaces.kicad_sch")
		(attr smd)
		(fp_rect
			(start -0.925 -0.47)
			(end 0.925 0.47)
			(stroke
				(width 0.05)
				(type default)
			)
			(fill no)
			(layer "F.CrtYd")
		)
		(fp_line
			(start 0.504 0.248)
			(end -0.494 0.248)
			(stroke
				(width 0.15)
				(type solid)
			)
			(layer "F.Fab")
		)
		(fp_line
			(start 0.504 -0.25)
			(end 0.504 0.248)
			(stroke
				(width 0.15)
				(type solid)
			)
			(layer "F.Fab")
		)
		(fp_line
			(start -0.494 0.248)
			(end -0.494 -0.25)
			(stroke
				(width 0.15)
				(type solid)
			)
			(layer "F.Fab")
		)
		(fp_line
			(start -0.494 -0.25)
			(end 0.504 -0.25)
			(stroke
				(width 0.15)
				(type solid)
			)
			(layer "F.Fab")
		)
		(pad "1" smd roundrect
			(at -0.48 0 180)
			(size 0.59 0.64)
			(layers "F.Cu" "F.Mask" "F.Paste")
			(roundrect_rratio 0.25)
			(net 1 "GND")
			(pintype "passive")
		)
		(pad "2" smd roundrect
			(at 0.48 0 180)
			(size 0.59 0.64)
			(layers "F.Cu" "F.Mask" "F.Paste")
			(roundrect_rratio 0.25)
			(net 2 "VCC3V3")
			(pintype "passive")
		)
	)
	(footprint "antmicro-footprints:R_0402_1005Metric"
		(layer "F.Cu")
		(at 83.09 165.065 90)
		(descr "Resistor SMD 0402")
		(tags "resistor SMD 0402")
		(property "Reference" "R12"
			(at -1.135 -0.59 90)
			(layer "F.SilkS")
			(effects
				(font
					(size 0.7 0.7)
					(thickness 0.15)
				)
				(justify left bottom)
			)
		)
		(property "Value" "R_200k_0402"
			(at 0 1.4 90)
			(layer "F.Fab")
			(effects
				(font
					(size 0.7 0.7)
					(thickness 0.15)
				)
				(justify left bottom)
			)
		)
		(property "Datasheet" "https://www.bourns.com/docs/product-datasheets/cr.pdf"
			(at 0 0 90)
			(layer "F.Fab")
			(hide yes)
			(effects
				(font
					(size 1.27 1.27)
					(thickness 0.15)
				)
			)
		)
		(property "Description" "SMD Chip Resistor, 200 kohm, ± 1%, 62.5 mW, 0402 [1005 Metric], Thick Film, General Purpose"
			(at 0 0 90)
			(layer "F.Fab")
			(hide yes)
			(effects
				(font
					(size 1.27 1.27)
					(thickness 0.15)
				)
			)
		)
		(property "Author" "Antmicro"
			(at 248.155 81.975 0)
			(layer "F.Fab")
			(hide yes)
			(effects
				(font
					(size 1 1)
					(thickness 0.15)
				)
			)
		)
		(property "License" "Apache-2.0"
			(at 248.155 81.975 0)
			(layer "F.Fab")
			(hide yes)
			(effects
				(font
					(size 1 1)
					(thickness 0.15)
				)
			)
		)
		(property "MPN" "CR0402-FX-2003GLF"
			(at 248.155 81.975 0)
			(layer "F.Fab")
			(hide yes)
			(effects
				(font
					(size 1 1)
					(thickness 0.15)
				)
			)
		)
		(property "Manufacturer" "Bourns"
			(at 248.155 81.975 0)
			(layer "F.Fab")
			(hide yes)
			(effects
				(font
					(size 1 1)
					(thickness 0.15)
				)
			)
		)
		(property "Tolerance" "1%"
			(at 248.155 81.975 0)
			(layer "F.Fab")
			(hide yes)
			(effects
				(font
					(size 1 1)
					(thickness 0.15)
				)
			)
		)
		(property "Val" "200k"
			(at 248.155 81.975 0)
			(layer "F.Fab")
			(hide yes)
			(effects
				(font
					(size 1 1)
					(thickness 0.15)
				)
			)
		)
		(sheetname "/Interfaces/")
		(sheetfile "interfaces.kicad_sch")
		(attr smd)
		(fp_rect
			(start -0.925 -0.47)
			(end 0.925 0.47)
			(stroke
				(width 0.05)
				(type default)
			)
			(fill no)
			(layer "F.CrtYd")
		)
		(fp_rect
			(start -0.5 -0.25)
			(end 0.5 0.25)
			(stroke
				(width 0.15)
				(type solid)
			)
			(fill no)
			(layer "F.Fab")
		)
		(pad "1" smd roundrect
			(at -0.48 0 90)
			(size 0.59 0.64)
			(layers "F.Cu" "F.Mask" "F.Paste")
			(roundrect_rratio 0.25)
			(net 312 "Net-(U21-EN)")
			(pintype "passive")
		)
		(pad "2" smd roundrect
			(at 0.48 0 90)
			(size 0.59 0.64)
			(layers "F.Cu" "F.Mask" "F.Paste")
			(roundrect_rratio 0.25)
			(net 2 "VCC3V3")
			(pintype "passive")
		)
	)
)
